# ZAIUS-LV_CARD-EVT1-X00-BOM-X01_20160825.xls — PWA BOM (bom)
| FOXCONN TECHNOLOGY GROUP |  |  |  |  |  |  |  |  |  |  |  |  |  |  |  |  |  |  |  |
| BILL OF MATERIAL |  |  |  |  |  |  |  |  |  |  |  |  |  |  |  |  |  |  |  |
| REV OF  BOM | X01 | CUSTOMER |  | DELL |  | CUSTOMER P/N |  | PWA P/N：10035W000-600-G | PWA DESCRIPTION | Peripheral Board,G,Zaius-LV Card |  |  | PRODUCT CODE |  |  | PWA  REV | X00 | DATE | 42608 |
| Sourcing (Single/Sole/Multi) | Critical Commodity (Y or N) | Component Class (1, 2, other) | Dell PSL (Y or N) | Line Item | Item Number | Foxconn P/N | Dell P/N | Part Description | Manufacturer  Full Name | Manufacturer  Part Number | Qty | RoHS Status | Location | CC Qual Build: | Qual by (Dell / ODM ?) | The Date of Change Part or Add 2nd Source | Configuration Identifier | Dell Comments | ODM Comments |
|  |  |  |  | 1 | 1 | 0101DUL00-000-G |  | PCB,Zaius-LV Card EVT-X00,OSP,Red,4L,1.5925*0.9953,G | GCE | 0101DUL00-000-G | 1 |  | PCB |  |  |  |  |  |  |
|  | N | ND | N | 2 | 2 | 610107A00-017-G | - | RES,0 Ohm,+/-5%,1/16W,G,SMD0402 | KOA SPEER ELECTRONICS, INC. | RK73Z1ETTP | 1 | N | R2 |  |  |  |  |  |  |
|  |  |  |  |  |  | 610107A00-024-G |  | RES,0 Ohm,+/-5%,1/16W,G,SMD0402 | PANASONIC INDUSTRIAL CO.,LTD. | ERJ2GE0R00X |  |  |  |  |  |  |  |  |  |
|  |  |  |  |  |  | 610107A00-029-G |  | RES,0 Ohm,+/-5%,1/16W,G,SMD0402 | VISHAY ENTER TECHNO LOGY.INC | CRCW04020000Z0ED |  |  |  |  |  |  |  |  |  |
|  | Y |  | N | 3 | 3 | 34131N000-G78-G |  | CONN,BTB,V/T,0.8mm,8u,G,SMD-80 | FCI CONNECTORS HONGKONG LTD. | 61083-081402LF | 2 |  | J1,J2 |  |  |  |  |  |  |
